FILE_TYPE = CONNECTIVITY;
{Allegro Design Entry HDL 16.6-p007 (v16-6-112F) 10/10/2012}
"PAGE_NUMBER" = 60;
0"NC";
1"M_K_DQS_DP<17:0>";
2"M_K_DQS_DN<17:0>";
3"M_K_MA<17:0>";
4"M_K_BA<1:0>";
5"M_K_BG<1:0>";
6"M_K_CKE<3:0>";
7"M_K_CS_N<7:0>";
8"M_K_ODT<3:0>";
9"M_K_DQ<63:0>";
10"M_K_CLK_DN<3:0>";
11"M_K_CLK_DP<3:0>";
12"M_K_ECC<7:0>";
13"M_K_C<2>";
14"M_K_ECC<0>";
15"M_K_ECC<1>";
16"M_K_ECC<2>";
17"M_K_ECC<3>";
18"M_K_ECC<4>";
19"M_K_ECC<5>";
20"M_K_ECC<6>";
21"M_K_ECC<7>";
22"M_K_DQ<0>";
23"M_K_DQ<1>";
24"M_K_DQ<2>";
25"M_K_DQ<3>";
26"M_K_DQ<4>";
27"M_K_DQ<5>";
28"M_K_DQ<6>";
29"M_K_DQ<7>";
30"M_K_DQ<8>";
31"M_K_DQ<9>";
32"M_K_DQ<10>";
33"M_K_CLK_DP<0>";
34"M_K_CLK_DP<1>";
35"M_K_CLK_DP<2>";
36"M_K_CLK_DP<3>";
37"M_K_CLK_DN<0>";
38"M_K_CLK_DN<1>";
39"M_K_CLK_DN<2>";
40"M_K_CLK_DN<3>";
41"M_K_DQ<11>";
42"M_K_DQ<12>";
43"M_K_DQ<13>";
44"M_K_DQ<14>";
45"M_K_DQ<15>";
46"M_K_DQ<16>";
47"M_K_DQ<17>";
48"M_K_DQ<18>";
49"M_K_DQ<19>";
50"M_K_DQ<20>";
51"M_K_DQ<21>";
52"M_K_DQ<22>";
53"M_K_DQ<23>";
54"M_K_DQ<24>";
55"M_K_DQ<25>";
56"M_K_DQ<26>";
57"M_K_DQ<27>";
58"M_K_DQ<28>";
59"M_K_DQ<29>";
60"M_K_DQ<30>";
61"M_K_DQ<31>";
62"M_K_DQ<32>";
63"M_K_DQ<33>";
64"M_K_DQ<34>";
65"M_K_DQ<35>";
66"M_K_DQ<36>";
67"M_K_DQ<37>";
68"M_K_DQ<38>";
69"M_K_DQ<39>";
70"M_K_DQ<40>";
71"M_K_DQ<41>";
72"M_K_DQ<42>";
73"M_K_DQ<43>";
74"M_K_DQ<44>";
75"M_K_DQ<45>";
76"M_K_DQ<46>";
77"M_K_DQ<47>";
78"M_K_DQ<48>";
79"M_K_DQ<49>";
80"M_K_DQ<50>";
81"M_K_DQ<51>";
82"M_K_DQ<52>";
83"M_K_DQ<53>";
84"M_K_DQ<54>";
85"M_K_DQ<55>";
86"M_K_DQ<56>";
87"M_K_DQ<57>";
88"M_K_DQ<58>";
89"M_K_DQ<59>";
90"M_K_DQ<60>";
91"M_K_DQ<61>";
92"M_K_DQ<62>";
93"M_K_DQ<63>";
94"M_K_ODT<0>";
95"M_K_ODT<1>";
96"M_K_ODT<2>";
97"M_K_ODT<3>";
98"M_K_MA<0>";
99"M_K_MA<1>";
100"M_K_MA<2>";
101"M_K_CS_N<0>";
102"M_K_CS_N<1>";
103"M_K_CS_N<2>";
104"M_K_CS_N<3>";
105"M_K_CS_N<4>";
106"M_K_CS_N<5>";
107"M_K_CS_N<6>";
108"M_K_CS_N<7>";
109"M_K_CKE<0>";
110"M_K_CKE<1>";
111"M_K_CKE<2>";
112"M_K_CKE<3>";
113"M_K_BG<0>";
114"M_K_BG<1>";
115"M_K_BA<0>";
116"M_K_BA<1>";
117"M_K_PAR";
118"M_K_ALERT_N";
119"M_K_ACT_N";
120"M_K_MA<3>";
121"M_K_MA<4>";
122"M_K_MA<5>";
123"M_K_MA<6>";
124"M_K_MA<7>";
125"M_K_MA<8>";
126"M_K_MA<9>";
127"M_K_MA<10>";
128"M_K_MA<11>";
129"M_K_MA<12>";
130"M_K_MA<13>";
131"M_K_MA<14>";
132"M_K_MA<15>";
133"M_K_MA<16>";
134"M_K_MA<17>";
135"M_K_DQS_DP<0>";
136"M_K_DQS_DP<1>";
137"M_K_DQS_DP<2>";
138"M_K_DQS_DP<3>";
139"M_K_DQS_DP<4>";
140"M_K_DQS_DP<5>";
141"M_K_DQS_DN<0>";
142"M_K_DQS_DN<1>";
143"M_K_DQS_DN<2>";
144"M_K_DQS_DN<3>";
145"M_K_DQS_DN<4>";
146"M_K_DQS_DN<5>";
147"M_K_DQS_DN<6>";
148"M_K_DQS_DN<7>";
149"M_K_DQS_DN<8>";
150"M_K_DQS_DN<9>";
151"M_K_DQS_DN<10>";
152"M_K_DQS_DN<11>";
153"M_K_DQS_DN<12>";
154"M_K_DQS_DN<13>";
155"M_K_DQS_DN<14>";
156"M_K_DQS_DN<15>";
157"M_K_DQS_DN<16>";
158"M_K_DQS_DN<17>";
159"M_K_DQS_DP<6>";
160"M_K_DQS_DP<7>";
161"M_K_DQS_DP<8>";
162"M_K_DQS_DP<9>";
163"M_K_DQS_DP<10>";
164"M_K_DQS_DP<11>";
165"M_K_DQS_DP<12>";
166"M_K_DQS_DP<13>";
167"M_K_DQS_DP<14>";
168"M_K_DQS_DP<15>";
169"M_K_DQS_DP<16>";
170"M_K_DQS_DP<17>";
%"TAP"
"6","(-5575,825)","0","mstr_standard","I10";
;
HDL_TAP"TRUE"
BODY_TYPE"PLUMBING"
CDS_LIB"mstr_standard";
"B \NAC \NWC"11;
"S \NAC"
BN"0"33;
%"TAP"
"6","(-2850,1575)","2","mstr_standard","I100";
;
HDL_TAP"TRUE"
BODY_TYPE"PLUMBING"
CDS_LIB"mstr_standard";
"B \NAC \NWC"8;
"S \NAC"
BN"3"97;
%"TAP"
"6","(-2850,1525)","2","mstr_standard","I101";
;
HDL_TAP"TRUE"
BODY_TYPE"PLUMBING"
CDS_LIB"mstr_standard";
"B \NAC \NWC"8;
"S \NAC"
BN"2"96;
%"TAP"
"6","(-2850,1475)","2","mstr_standard","I102";
;
HDL_TAP"TRUE"
BODY_TYPE"PLUMBING"
CDS_LIB"mstr_standard";
"B \NAC \NWC"8;
"S \NAC"
BN"1"95;
%"TAP"
"6","(-2850,1675)","2","mstr_standard","I103";
;
HDL_TAP"TRUE"
BODY_TYPE"PLUMBING"
CDS_LIB"mstr_standard";
"B \NAC \NWC"6;
"S \NAC"
BN"0"109;
%"TAP"
"6","(-2850,1725)","2","mstr_standard","I104";
;
HDL_TAP"TRUE"
BODY_TYPE"PLUMBING"
CDS_LIB"mstr_standard";
"B \NAC \NWC"6;
"S \NAC"
BN"1"110;
%"TAP"
"6","(-2850,1775)","2","mstr_standard","I105";
;
HDL_TAP"TRUE"
BODY_TYPE"PLUMBING"
CDS_LIB"mstr_standard";
"B \NAC \NWC"6;
"S \NAC"
BN"2"111;
%"TAP"
"6","(-2850,1825)","2","mstr_standard","I106";
;
HDL_TAP"TRUE"
BODY_TYPE"PLUMBING"
CDS_LIB"mstr_standard";
"B \NAC \NWC"6;
"S \NAC"
BN"3"112;
%"TAP"
"6","(-2850,1925)","2","mstr_standard","I107";
;
HDL_TAP"TRUE"
BODY_TYPE"PLUMBING"
CDS_LIB"mstr_standard";
"B \NAC \NWC"3;
"S \NAC"
BN"0"98;
%"TAP"
"6","(-2850,1975)","2","mstr_standard","I108";
;
HDL_TAP"TRUE"
BODY_TYPE"PLUMBING"
CDS_LIB"mstr_standard";
"B \NAC \NWC"3;
"S \NAC"
BN"1"99;
%"TAP"
"6","(-2850,2075)","2","mstr_standard","I109";
;
HDL_TAP"TRUE"
BODY_TYPE"PLUMBING"
CDS_LIB"mstr_standard";
"B \NAC \NWC"3;
"S \NAC"
BN"3"120;
%"TAP"
"6","(-5575,925)","0","mstr_standard","I11";
;
HDL_TAP"TRUE"
BODY_TYPE"PLUMBING"
CDS_LIB"mstr_standard";
"B \NAC \NWC"11;
"S \NAC"
BN"2"35;
%"TAP"
"6","(-2850,2025)","2","mstr_standard","I110";
;
HDL_TAP"TRUE"
BODY_TYPE"PLUMBING"
CDS_LIB"mstr_standard";
"B \NAC \NWC"3;
"S \NAC"
BN"2"100;
%"TAP"
"6","(-2850,2125)","2","mstr_standard","I111";
;
HDL_TAP"TRUE"
BODY_TYPE"PLUMBING"
CDS_LIB"mstr_standard";
"B \NAC \NWC"3;
"S \NAC"
BN"4"121;
%"TAP"
"6","(-2850,2175)","2","mstr_standard","I112";
;
HDL_TAP"TRUE"
BODY_TYPE"PLUMBING"
CDS_LIB"mstr_standard";
"B \NAC \NWC"3;
"S \NAC"
BN"5"122;
%"TAP"
"6","(-2850,2225)","2","mstr_standard","I113";
;
HDL_TAP"TRUE"
BODY_TYPE"PLUMBING"
CDS_LIB"mstr_standard";
"B \NAC \NWC"3;
"S \NAC"
BN"6"123;
%"TAP"
"6","(-2850,2325)","2","mstr_standard","I114";
;
HDL_TAP"TRUE"
BODY_TYPE"PLUMBING"
CDS_LIB"mstr_standard";
"B \NAC \NWC"3;
"S \NAC"
BN"8"125;
%"TAP"
"6","(-2850,2275)","2","mstr_standard","I115";
;
HDL_TAP"TRUE"
BODY_TYPE"PLUMBING"
CDS_LIB"mstr_standard";
"B \NAC \NWC"3;
"S \NAC"
BN"7"124;
%"TAP"
"6","(-2850,2475)","2","mstr_standard","I116";
;
HDL_TAP"TRUE"
BODY_TYPE"PLUMBING"
CDS_LIB"mstr_standard";
"B \NAC \NWC"3;
"S \NAC"
BN"11"128;
%"TAP"
"6","(-2850,2425)","2","mstr_standard","I117";
;
HDL_TAP"TRUE"
BODY_TYPE"PLUMBING"
CDS_LIB"mstr_standard";
"B \NAC \NWC"3;
"S \NAC"
BN"10"127;
%"TAP"
"6","(-2850,2375)","2","mstr_standard","I118";
;
HDL_TAP"TRUE"
BODY_TYPE"PLUMBING"
CDS_LIB"mstr_standard";
"B \NAC \NWC"3;
"S \NAC"
BN"9"126;
%"TAP"
"6","(-2850,2525)","2","mstr_standard","I119";
;
HDL_TAP"TRUE"
BODY_TYPE"PLUMBING"
CDS_LIB"mstr_standard";
"B \NAC \NWC"3;
"S \NAC"
BN"12"129;
%"TAP"
"6","(-5575,975)","0","mstr_standard","I12";
;
HDL_TAP"TRUE"
BODY_TYPE"PLUMBING"
CDS_LIB"mstr_standard";
"B \NAC \NWC"11;
"S \NAC"
BN"3"36;
%"TAP"
"6","(-2850,2575)","2","mstr_standard","I120";
;
HDL_TAP"TRUE"
BODY_TYPE"PLUMBING"
CDS_LIB"mstr_standard";
"B \NAC \NWC"3;
"S \NAC"
BN"13"130;
%"TAP"
"6","(-2850,2625)","2","mstr_standard","I121";
;
HDL_TAP"TRUE"
BODY_TYPE"PLUMBING"
CDS_LIB"mstr_standard";
"B \NAC \NWC"3;
"S \NAC"
BN"14"131;
%"TAP"
"6","(-2850,2675)","2","mstr_standard","I122";
;
HDL_TAP"TRUE"
BODY_TYPE"PLUMBING"
CDS_LIB"mstr_standard";
"B \NAC \NWC"3;
"S \NAC"
BN"15"132;
%"TAP"
"6","(-2850,2725)","2","mstr_standard","I123";
;
HDL_TAP"TRUE"
BODY_TYPE"PLUMBING"
CDS_LIB"mstr_standard";
"B \NAC \NWC"3;
"S \NAC"
BN"16"133;
%"TAP"
"6","(-2850,2775)","2","mstr_standard","I124";
;
HDL_TAP"TRUE"
BODY_TYPE"PLUMBING"
CDS_LIB"mstr_standard";
"B \NAC \NWC"3;
"S \NAC"
BN"17"134;
%"TAP"
"6","(-2850,2925)","2","mstr_standard","I125";
;
HDL_TAP"TRUE"
BODY_TYPE"PLUMBING"
CDS_LIB"mstr_standard";
"B \NAC \NWC"2;
"S \NAC"
BN"1"142;
%"TAP"
"6","(-2850,2975)","2","mstr_standard","I126";
;
HDL_TAP"TRUE"
BODY_TYPE"PLUMBING"
CDS_LIB"mstr_standard";
"B \NAC \NWC"2;
"S \NAC"
BN"2"143;
%"TAP"
"6","(-2850,2875)","2","mstr_standard","I127";
;
HDL_TAP"TRUE"
BODY_TYPE"PLUMBING"
CDS_LIB"mstr_standard";
"B \NAC \NWC"2;
"S \NAC"
BN"0"141;
%"TAP"
"6","(-2850,3075)","2","mstr_standard","I128";
;
HDL_TAP"TRUE"
BODY_TYPE"PLUMBING"
CDS_LIB"mstr_standard";
"B \NAC \NWC"2;
"S \NAC"
BN"4"145;
%"TAP"
"6","(-2850,3025)","2","mstr_standard","I129";
;
HDL_TAP"TRUE"
BODY_TYPE"PLUMBING"
CDS_LIB"mstr_standard";
"B \NAC \NWC"2;
"S \NAC"
BN"3"144;
%"TAP"
"6","(-5575,1075)","0","mstr_standard","I13";
;
HDL_TAP"TRUE"
BODY_TYPE"PLUMBING"
CDS_LIB"mstr_standard";
"B \NAC \NWC"12;
"S \NAC"
BN"0"14;
%"TAP"
"6","(-2850,3125)","2","mstr_standard","I130";
;
HDL_TAP"TRUE"
BODY_TYPE"PLUMBING"
CDS_LIB"mstr_standard";
"B \NAC \NWC"2;
"S \NAC"
BN"5"146;
%"TAP"
"6","(-2850,3175)","2","mstr_standard","I131";
;
HDL_TAP"TRUE"
BODY_TYPE"PLUMBING"
CDS_LIB"mstr_standard";
"B \NAC \NWC"2;
"S \NAC"
BN"6"147;
%"TAP"
"6","(-2850,3225)","2","mstr_standard","I132";
;
HDL_TAP"TRUE"
BODY_TYPE"PLUMBING"
CDS_LIB"mstr_standard";
"B \NAC \NWC"2;
"S \NAC"
BN"7"148;
%"TAP"
"6","(-2850,3275)","2","mstr_standard","I133";
;
HDL_TAP"TRUE"
BODY_TYPE"PLUMBING"
CDS_LIB"mstr_standard";
"B \NAC \NWC"2;
"S \NAC"
BN"8"149;
%"TAP"
"6","(-2850,3325)","2","mstr_standard","I134";
;
HDL_TAP"TRUE"
BODY_TYPE"PLUMBING"
CDS_LIB"mstr_standard";
"B \NAC \NWC"2;
"S \NAC"
BN"9"150;
%"TAP"
"6","(-2850,3375)","2","mstr_standard","I135";
;
HDL_TAP"TRUE"
BODY_TYPE"PLUMBING"
CDS_LIB"mstr_standard";
"B \NAC \NWC"2;
"S \NAC"
BN"10"151;
%"TAP"
"6","(-2850,3475)","2","mstr_standard","I136";
;
HDL_TAP"TRUE"
BODY_TYPE"PLUMBING"
CDS_LIB"mstr_standard";
"B \NAC \NWC"2;
"S \NAC"
BN"12"153;
%"TAP"
"6","(-2850,3425)","2","mstr_standard","I137";
;
HDL_TAP"TRUE"
BODY_TYPE"PLUMBING"
CDS_LIB"mstr_standard";
"B \NAC \NWC"2;
"S \NAC"
BN"11"152;
%"TAP"
"6","(-2850,3625)","2","mstr_standard","I138";
;
HDL_TAP"TRUE"
BODY_TYPE"PLUMBING"
CDS_LIB"mstr_standard";
"B \NAC \NWC"2;
"S \NAC"
BN"15"156;
%"TAP"
"6","(-2850,3575)","2","mstr_standard","I139";
;
HDL_TAP"TRUE"
BODY_TYPE"PLUMBING"
CDS_LIB"mstr_standard";
"B \NAC \NWC"2;
"S \NAC"
BN"14"155;
%"TAP"
"6","(-5575,1125)","0","mstr_standard","I14";
;
HDL_TAP"TRUE"
BODY_TYPE"PLUMBING"
CDS_LIB"mstr_standard";
"B \NAC \NWC"12;
"S \NAC"
BN"1"15;
%"TAP"
"6","(-2850,3525)","2","mstr_standard","I140";
;
HDL_TAP"TRUE"
BODY_TYPE"PLUMBING"
CDS_LIB"mstr_standard";
"B \NAC \NWC"2;
"S \NAC"
BN"13"154;
%"TAP"
"6","(-2850,3675)","2","mstr_standard","I141";
;
HDL_TAP"TRUE"
BODY_TYPE"PLUMBING"
CDS_LIB"mstr_standard";
"B \NAC \NWC"2;
"S \NAC"
BN"16"157;
%"TAP"
"6","(-2850,3725)","2","mstr_standard","I142";
;
HDL_TAP"TRUE"
BODY_TYPE"PLUMBING"
CDS_LIB"mstr_standard";
"B \NAC \NWC"2;
"S \NAC"
BN"17"158;
%"TAP"
"6","(-2850,3825)","2","mstr_standard","I143";
;
HDL_TAP"TRUE"
BODY_TYPE"PLUMBING"
CDS_LIB"mstr_standard";
"B \NAC \NWC"1;
"S \NAC"
BN"0"135;
%"TAP"
"6","(-2850,3875)","2","mstr_standard","I144";
;
HDL_TAP"TRUE"
BODY_TYPE"PLUMBING"
CDS_LIB"mstr_standard";
"B \NAC \NWC"1;
"S \NAC"
BN"1"136;
%"TAP"
"6","(-2850,3925)","2","mstr_standard","I145";
;
HDL_TAP"TRUE"
BODY_TYPE"PLUMBING"
CDS_LIB"mstr_standard";
"B \NAC \NWC"1;
"S \NAC"
BN"2"137;
%"TAP"
"6","(-2850,3975)","2","mstr_standard","I146";
;
HDL_TAP"TRUE"
BODY_TYPE"PLUMBING"
CDS_LIB"mstr_standard";
"B \NAC \NWC"1;
"S \NAC"
BN"3"138;
%"TAP"
"6","(-5575,1175)","0","mstr_standard","I15";
;
HDL_TAP"TRUE"
BODY_TYPE"PLUMBING"
CDS_LIB"mstr_standard";
"B \NAC \NWC"12;
"S \NAC"
BN"2"16;
%"TAP"
"6","(-2850,4025)","2","mstr_standard","I157";
;
HDL_TAP"TRUE"
BODY_TYPE"PLUMBING"
CDS_LIB"mstr_standard";
"B \NAC \NWC"1;
"S \NAC"
BN"4"139;
%"TAP"
"6","(-2850,4125)","2","mstr_standard","I158";
;
HDL_TAP"TRUE"
BODY_TYPE"PLUMBING"
CDS_LIB"mstr_standard";
"B \NAC \NWC"1;
"S \NAC"
BN"6"159;
%"TAP"
"6","(-2850,4075)","2","mstr_standard","I159";
;
HDL_TAP"TRUE"
BODY_TYPE"PLUMBING"
CDS_LIB"mstr_standard";
"B \NAC \NWC"1;
"S \NAC"
BN"5"140;
%"TAP"
"6","(-5575,1275)","0","mstr_standard","I16";
;
HDL_TAP"TRUE"
BODY_TYPE"PLUMBING"
CDS_LIB"mstr_standard";
"B \NAC \NWC"12;
"S \NAC"
BN"4"18;
%"TAP"
"6","(-2850,4175)","2","mstr_standard","I160";
;
HDL_TAP"TRUE"
BODY_TYPE"PLUMBING"
CDS_LIB"mstr_standard";
"B \NAC \NWC"1;
"S \NAC"
BN"7"160;
%"TAP"
"6","(-2850,4225)","2","mstr_standard","I161";
;
HDL_TAP"TRUE"
BODY_TYPE"PLUMBING"
CDS_LIB"mstr_standard";
"B \NAC \NWC"1;
"S \NAC"
BN"8"161;
%"TAP"
"6","(-2850,4275)","2","mstr_standard","I162";
;
HDL_TAP"TRUE"
BODY_TYPE"PLUMBING"
CDS_LIB"mstr_standard";
"B \NAC \NWC"1;
"S \NAC"
BN"9"162;
%"TAP"
"6","(-2850,4325)","2","mstr_standard","I163";
;
HDL_TAP"TRUE"
BODY_TYPE"PLUMBING"
CDS_LIB"mstr_standard";
"B \NAC \NWC"1;
"S \NAC"
BN"10"163;
%"TAP"
"6","(-2850,4375)","2","mstr_standard","I164";
;
HDL_TAP"TRUE"
BODY_TYPE"PLUMBING"
CDS_LIB"mstr_standard";
"B \NAC \NWC"1;
"S \NAC"
BN"11"164;
%"TAP"
"6","(-2850,4525)","2","mstr_standard","I165";
;
HDL_TAP"TRUE"
BODY_TYPE"PLUMBING"
CDS_LIB"mstr_standard";
"B \NAC \NWC"1;
"S \NAC"
BN"14"167;
%"TAP"
"6","(-2850,4475)","2","mstr_standard","I166";
;
HDL_TAP"TRUE"
BODY_TYPE"PLUMBING"
CDS_LIB"mstr_standard";
"B \NAC \NWC"1;
"S \NAC"
BN"13"166;
%"TAP"
"6","(-2850,4425)","2","mstr_standard","I167";
;
HDL_TAP"TRUE"
BODY_TYPE"PLUMBING"
CDS_LIB"mstr_standard";
"B \NAC \NWC"1;
"S \NAC"
BN"12"165;
%"TAP"
"6","(-2850,4575)","2","mstr_standard","I168";
;
HDL_TAP"TRUE"
BODY_TYPE"PLUMBING"
CDS_LIB"mstr_standard";
"B \NAC \NWC"1;
"S \NAC"
BN"15"168;
%"TAP"
"6","(-2850,4625)","2","mstr_standard","I169";
;
HDL_TAP"TRUE"
BODY_TYPE"PLUMBING"
CDS_LIB"mstr_standard";
"B \NAC \NWC"1;
"S \NAC"
BN"16"169;
%"TAP"
"6","(-5575,1225)","0","mstr_standard","I17";
;
HDL_TAP"TRUE"
BODY_TYPE"PLUMBING"
CDS_LIB"mstr_standard";
"B \NAC \NWC"12;
"S \NAC"
BN"3"17;
%"TAP"
"6","(-2850,4675)","2","mstr_standard","I170";
;
HDL_TAP"TRUE"
BODY_TYPE"PLUMBING"
CDS_LIB"mstr_standard";
"B \NAC \NWC"1;
"S \NAC"
BN"17"170;
%"SKX_EXT_B"
"6","(-4175,2575)","0","chpset_lib","I172";
;
CDS_SEC"6"
CDS_LOCATION"U2D1"
SEC"6"
CDS_LIB"chpset_lib"
SEC_TYPE"BGA1"
PACK_TYPE"BGA1"
MATERIAL"IC"
PART_NUMBER"TBD"
LOCATION"U2D1";
"DDR3_PAR"
$PN"ED53"117;
"DDR3_ODT<0>"
$PN"EE50"94;
"DDR3_ODT<1>"
$PN"EE48"95;
"DDR3_ODT<2>"
$PN"EA50"96;
"DDR3_ODT<3>"
$PN"EA48"97;
"DDR3_MA<0>"
$PN"EB53"98;
"DDR3_MA<1>"
$PN"ED57"99;
"DDR3_MA<2>"
$PN"EE58"100;
"DDR3_MA<3>"
$PN"EB57"120;
"DDR3_MA<4>"
$PN"ED59"121;
"DDR3_MA<5>"
$PN"EA58"122;
"DDR3_MA<6>"
$PN"EE60"123;
"DDR3_MA<7>"
$PN"EA60"124;
"DDR3_MA<8>"
$PN"EB59"125;
"DDR3_MA<9>"
$PN"EF61"126;
"DDR3_MA<10>"
$PN"DW54"127;
"DDR3_MA<11>"
$PN"EB61"128;
"DDR3_MA<12>"
$PN"DT63"129;
"DDR3_MA<13>"
$PN"DW48"130;
"DDR3_MA<14>"
$PN"ED51"131;
"DDR3_MA<15>"
$PN"DV49"132;
"DDR3_MA<16>"
$PN"EA52"133;
"DDR3_MA<17>"
$PN"EA46"134;
"DDR3_ECC<0>"
$PN"DA68"14;
"DDR3_ECC<1>"
$PN"DE68"15;
"DDR3_ECC<2>"
$PN"DB65"16;
"DDR3_ECC<3>"
$PN"DD65"17;
"DDR3_ECC<4>"
$PN"DB69"18;
"DDR3_ECC<5>"
$PN"DD69"19;
"DDR3_ECC<6>"
$PN"DA66"20;
"DDR3_ECC<7>"
$PN"DE66"21;
"DDR3_DQS_DP<0>"
$PN"CV85"135;
"DDR3_DQS_DP<1>"
$PN"DP85"136;
"DDR3_DQS_DP<2>"
$PN"DM81"137;
"DDR3_DQS_DP<3>"
$PN"DT75"138;
"DDR3_DQS_DP<4>"
$PN"EC38"139;
"DDR3_DQS_DP<5>"
$PN"DT35"140;
"DDR3_DQS_DP<6>"
$PN"DT29"159;
"DDR3_DQS_DP<7>"
$PN"DT23"160;
"DDR3_DQS_DP<8>"
$PN"DD67"161;
"DDR3_DQS_DP<9>"
$PN"CP85"162;
"DDR3_DQS_DP<10>"
$PN"DL84"163;
"DDR3_DQS_DP<11>"
$PN"DP79"164;
"DDR3_DQS_DP<12>"
$PN"DM75"165;
"DDR3_DQS_DP<13>"
$PN"DW38"166;
"DDR3_DQS_DP<14>"
$PN"DM35"167;
"DDR3_DQS_DP<15>"
$PN"DP29"168;
"DDR3_DQS_DP<16>"
$PN"DP23"169;
"DDR3_DQS_DP<17>"
$PN"CY67"170;
"DDR3_DQS_DN<0>"
$PN"CU84"141;
"DDR3_DQS_DN<1>"
$PN"DN84"142;
"DDR3_DQS_DN<2>"
$PN"DL82"143;
"DDR3_DQS_DN<3>"
$PN"DV75"144;
"DDR3_DQS_DN<4>"
$PN"EE38"145;
"DDR3_DQS_DN<5>"
$PN"DV35"146;
"DDR3_DQS_DN<6>"
$PN"DV29"147;
"DDR3_DQS_DN<7>"
$PN"DV23"148;
"DDR3_DQS_DN<8>"
$PN"DF67"149;
"DDR3_DQS_DN<9>"
$PN"CR84"150;
"DDR3_DQS_DN<10>"
$PN"DM85"151;
"DDR3_DQS_DN<11>"
$PN"DN80"152;
"DDR3_DQS_DN<12>"
$PN"DP75"153;
"DDR3_DQS_DN<13>"
$PN"EA38"154;
"DDR3_DQS_DN<14>"
$PN"DP35"155;
"DDR3_DQS_DN<15>"
$PN"DM29"156;
"DDR3_DQS_DN<16>"
$PN"DM23"157;
"DDR3_DQS_DN<17>"
$PN"DB67"158;
"DDR3_DQ<0>"
$PN"CN84"22;
"DDR3_DQ<1>"
$PN"CN86"23;
"DDR3_DQ<2>"
$PN"DA86"24;
"DDR3_DQ<3>"
$PN"DA84"25;
"DDR3_DQ<4>"
$PN"CL84"26;
"DDR3_DQ<5>"
$PN"CL86"27;
"DDR3_DQ<6>"
$PN"CW86"28;
"DDR3_DQ<7>"
$PN"CW84"29;
"DDR3_DQ<8>"
$PN"DG84"30;
"DDR3_DQ<9>"
$PN"DH85"31;
"DDR3_DQ<10>"
$PN"DV83"32;
"DDR3_DQ<11>"
$PN"DY83"41;
"DDR3_DQ<12>"
$PN"DD85"42;
"DDR3_DQ<13>"
$PN"DE84"43;
"DDR3_DQ<14>"
$PN"DR84"44;
"DDR3_DQ<15>"
$PN"DV85"45;
"DDR3_DQ<16>"
$PN"DM79"46;
"DDR3_DQ<17>"
$PN"DK81"47;
"DDR3_DQ<18>"
$PN"DT81"48;
"DDR3_DQ<19>"
$PN"DR82"49;
"DDR3_DQ<20>"
$PN"DK79"50;
"DDR3_DQ<21>"
$PN"DJ80"51;
"DDR3_DQ<22>"
$PN"DR80"52;
"DDR3_DQ<23>"
$PN"DN82"53;
"DDR3_DQ<24>"
$PN"DN76"54;
"DDR3_DQ<25>"
$PN"DU76"55;
"DDR3_DQ<26>"
$PN"DP73"56;
"DDR3_DQ<27>"
$PN"DT73"57;
"DDR3_DQ<28>"
$PN"DP77"58;
"DDR3_DQ<29>"
$PN"DT77"59;
"DDR3_DQ<30>"
$PN"DN74"60;
"DDR3_DQ<31>"
$PN"DU74"61;
"DDR3_DQ<32>"
$PN"EC40"62;
"DDR3_DQ<33>"
$PN"ED39"63;
"DDR3_DQ<34>"
$PN"EA36"64;
"DDR3_DQ<35>"
$PN"EC36"65;
"DDR3_DQ<36>"
$PN"DY39"66;
"DDR3_DQ<37>"
$PN"EA40"67;
"DDR3_DQ<38>"
$PN"DY37"68;
"DDR3_DQ<39>"
$PN"ED37"69;
"DDR3_DQ<40>"
$PN"DN36"70;
"DDR3_DQ<41>"
$PN"DU36"71;
"DDR3_DQ<42>"
$PN"DP33"72;
"DDR3_DQ<43>"
$PN"DT33"73;
"DDR3_DQ<44>"
$PN"DP37"74;
"DDR3_DQ<45>"
$PN"DT37"75;
"DDR3_DQ<46>"
$PN"DN34"76;
"DDR3_DQ<47>"
$PN"DU34"77;
"DDR3_DQ<48>"
$PN"DN30"78;
"DDR3_DQ<49>"
$PN"DU30"79;
"DDR3_DQ<50>"
$PN"DP27"80;
"DDR3_DQ<51>"
$PN"DT27"81;
"DDR3_DQ<52>"
$PN"DP31"82;
"DDR3_DQ<53>"
$PN"DT31"83;
"DDR3_DQ<54>"
$PN"DN28"84;
"DDR3_DQ<55>"
$PN"DU28"85;
"DDR3_DQ<56>"
$PN"DN24"86;
"DDR3_DQ<57>"
$PN"DU24"87;
"DDR3_DQ<58>"
$PN"DY21"88;
"DDR3_DQ<59>"
$PN"EB21"89;
"DDR3_DQ<60>"
$PN"DP25"90;
"DDR3_DQ<61>"
$PN"DT25"91;
"DDR3_DQ<62>"
$PN"EC22"92;
"DDR3_DQ<63>"
$PN"DW22"93;
"DDR3_CS_N<0>"
$PN"EF51"101;
"DDR3_CS_N<1>"
$PN"ED49"102;
"DDR3_CS_N<2>"
$PN"ED47"103;
"DDR3_CS_N<3>"
$PN"EB47"104;
"DDR3_CS_N<4>"
$PN"EB51"105;
"DDR3_CS_N<5>"
$PN"EB49"106;
"DDR3_CS_N<6>"
$PN"DV45"107;
"DDR3_CS_N<7>"
$PN"EB45"108;
"DDR3_CLK_DP<0>"
$PN"EB55"33;
"DDR3_CLK_DP<1>"
$PN"EE54"34;
"DDR3_CLK_DP<2>"
$PN"EA56"35;
"DDR3_CLK_DP<3>"
$PN"EE56"36;
"DDR3_CLK_DN<0>"
$PN"ED55"37;
"DDR3_CLK_DN<1>"
$PN"EF55"38;
"DDR3_CLK_DN<2>"
$PN"DW56"39;
"DDR3_CLK_DN<3>"
$PN"EF57"40;
"DDR3_CKE<0>"
$PN"EE62"109;
"DDR3_CKE<1>"
$PN"EF63"110;
"DDR3_CKE<2>"
$PN"EA62"111;
"DDR3_CKE<3>"
$PN"EB63"112;
"DDR3_CID<2>"
$PN"DV47"13;
"DDR3_BG<0>"
$PN"ED61"113;
"DDR3_BG<1>"
$PN"DW62"114;
"DDR3_BA<0>"
$PN"EE52"115;
"DDR3_BA<1>"
$PN"EA54"116;
"DDR3_ALERT_N"
$PN"ED63"118;
"DDR3_ACT_N"
$PN"DW60"119;
%"TAP"
"6","(-5575,1325)","0","mstr_standard","I18";
;
HDL_TAP"TRUE"
BODY_TYPE"PLUMBING"
CDS_LIB"mstr_standard";
"B \NAC \NWC"12;
"S \NAC"
BN"5"19;
%"TAP"
"6","(-5575,1375)","0","mstr_standard","I19";
;
HDL_TAP"TRUE"
BODY_TYPE"PLUMBING"
CDS_LIB"mstr_standard";
"B \NAC \NWC"12;
"S \NAC"
BN"6"20;
%"TAP"
"6","(-5575,1425)","0","mstr_standard","I20";
;
HDL_TAP"TRUE"
BODY_TYPE"PLUMBING"
CDS_LIB"mstr_standard";
"B \NAC \NWC"12;
"S \NAC"
BN"7"21;
%"TAP"
"6","(-5575,1525)","0","mstr_standard","I21";
;
HDL_TAP"TRUE"
BODY_TYPE"PLUMBING"
CDS_LIB"mstr_standard";
"B \NAC \NWC"9;
"S \NAC"
BN"0"22;
%"TAP"
"6","(-5575,1575)","0","mstr_standard","I22";
;
HDL_TAP"TRUE"
BODY_TYPE"PLUMBING"
CDS_LIB"mstr_standard";
"B \NAC \NWC"9;
"S \NAC"
BN"1"23;
%"TAP"
"6","(-5575,1625)","0","mstr_standard","I23";
;
HDL_TAP"TRUE"
BODY_TYPE"PLUMBING"
CDS_LIB"mstr_standard";
"B \NAC \NWC"9;
"S \NAC"
BN"2"24;
%"TAP"
"6","(-5575,1675)","0","mstr_standard","I24";
;
HDL_TAP"TRUE"
BODY_TYPE"PLUMBING"
CDS_LIB"mstr_standard";
"B \NAC \NWC"9;
"S \NAC"
BN"3"25;
%"TAP"
"6","(-5575,1725)","0","mstr_standard","I25";
;
HDL_TAP"TRUE"
BODY_TYPE"PLUMBING"
CDS_LIB"mstr_standard";
"B \NAC \NWC"9;
"S \NAC"
BN"4"26;
%"TAP"
"6","(-5575,1775)","0","mstr_standard","I26";
;
HDL_TAP"TRUE"
BODY_TYPE"PLUMBING"
CDS_LIB"mstr_standard";
"B \NAC \NWC"9;
"S \NAC"
BN"5"27;
%"TAP"
"6","(-5575,1825)","0","mstr_standard","I27";
;
HDL_TAP"TRUE"
BODY_TYPE"PLUMBING"
CDS_LIB"mstr_standard";
"B \NAC \NWC"9;
"S \NAC"
BN"6"28;
%"TAP"
"6","(-5575,1925)","0","mstr_standard","I28";
;
HDL_TAP"TRUE"
BODY_TYPE"PLUMBING"
CDS_LIB"mstr_standard";
"B \NAC \NWC"9;
"S \NAC"
BN"8"30;
%"TAP"
"6","(-5575,1875)","0","mstr_standard","I29";
;
HDL_TAP"TRUE"
BODY_TYPE"PLUMBING"
CDS_LIB"mstr_standard";
"B \NAC \NWC"9;
"S \NAC"
BN"7"29;
%"TAP"
"6","(-5575,1975)","0","mstr_standard","I31";
;
HDL_TAP"TRUE"
BODY_TYPE"PLUMBING"
CDS_LIB"mstr_standard";
"B \NAC \NWC"9;
"S \NAC"
BN"9"31;
%"TAP"
"6","(-5575,2025)","0","mstr_standard","I32";
;
HDL_TAP"TRUE"
BODY_TYPE"PLUMBING"
CDS_LIB"mstr_standard";
"B \NAC \NWC"9;
"S \NAC"
BN"10"32;
%"TAP"
"6","(-5575,2075)","0","mstr_standard","I33";
;
HDL_TAP"TRUE"
BODY_TYPE"PLUMBING"
CDS_LIB"mstr_standard";
"B \NAC \NWC"9;
"S \NAC"
BN"11"41;
%"TAP"
"6","(-5575,2125)","0","mstr_standard","I34";
;
HDL_TAP"TRUE"
BODY_TYPE"PLUMBING"
CDS_LIB"mstr_standard";
"B \NAC \NWC"9;
"S \NAC"
BN"12"42;
%"TAP"
"6","(-5575,2175)","0","mstr_standard","I35";
;
HDL_TAP"TRUE"
BODY_TYPE"PLUMBING"
CDS_LIB"mstr_standard";
"B \NAC \NWC"9;
"S \NAC"
BN"13"43;
%"TAP"
"6","(-5575,2225)","0","mstr_standard","I36";
;
HDL_TAP"TRUE"
BODY_TYPE"PLUMBING"
CDS_LIB"mstr_standard";
"B \NAC \NWC"9;
"S \NAC"
BN"14"44;
%"TAP"
"6","(-5575,2275)","0","mstr_standard","I37";
;
HDL_TAP"TRUE"
BODY_TYPE"PLUMBING"
CDS_LIB"mstr_standard";
"B \NAC \NWC"9;
"S \NAC"
BN"15"45;
%"TAP"
"6","(-5575,2325)","0","mstr_standard","I38";
;
HDL_TAP"TRUE"
BODY_TYPE"PLUMBING"
CDS_LIB"mstr_standard";
"B \NAC \NWC"9;
"S \NAC"
BN"16"46;
%"TAP"
"6","(-5575,2375)","0","mstr_standard","I39";
;
HDL_TAP"TRUE"
BODY_TYPE"PLUMBING"
CDS_LIB"mstr_standard";
"B \NAC \NWC"9;
"S \NAC"
BN"17"47;
%"TAP"
"6","(-5575,2425)","0","mstr_standard","I40";
;
HDL_TAP"TRUE"
BODY_TYPE"PLUMBING"
CDS_LIB"mstr_standard";
"B \NAC \NWC"9;
"S \NAC"
BN"18"48;
%"TAP"
"6","(-5575,2475)","0","mstr_standard","I41";
;
HDL_TAP"TRUE"
BODY_TYPE"PLUMBING"
CDS_LIB"mstr_standard";
"B \NAC \NWC"9;
"S \NAC"
BN"19"49;
%"TAP"
"6","(-5575,2525)","0","mstr_standard","I42";
;
HDL_TAP"TRUE"
BODY_TYPE"PLUMBING"
CDS_LIB"mstr_standard";
"B \NAC \NWC"9;
"S \NAC"
BN"20"50;
%"TAP"
"6","(-5575,2575)","0","mstr_standard","I43";
;
HDL_TAP"TRUE"
BODY_TYPE"PLUMBING"
CDS_LIB"mstr_standard";
"B \NAC \NWC"9;
"S \NAC"
BN"21"51;
%"TAP"
"6","(-5575,2625)","0","mstr_standard","I44";
;
HDL_TAP"TRUE"
BODY_TYPE"PLUMBING"
CDS_LIB"mstr_standard";
"B \NAC \NWC"9;
"S \NAC"
BN"22"52;
%"TAP"
"6","(-5575,2675)","0","mstr_standard","I45";
;
HDL_TAP"TRUE"
BODY_TYPE"PLUMBING"
CDS_LIB"mstr_standard";
"B \NAC \NWC"9;
"S \NAC"
BN"23"53;
%"TAP"
"6","(-5575,2725)","0","mstr_standard","I46";
;
HDL_TAP"TRUE"
BODY_TYPE"PLUMBING"
CDS_LIB"mstr_standard";
"B \NAC \NWC"9;
"S \NAC"
BN"24"54;
%"TAP"
"6","(-5575,2825)","0","mstr_standard","I47";
;
HDL_TAP"TRUE"
BODY_TYPE"PLUMBING"
CDS_LIB"mstr_standard";
"B \NAC \NWC"9;
"S \NAC"
BN"26"56;
%"TAP"
"6","(-5575,2775)","0","mstr_standard","I48";
;
HDL_TAP"TRUE"
BODY_TYPE"PLUMBING"
CDS_LIB"mstr_standard";
"B \NAC \NWC"9;
"S \NAC"
BN"25"55;
%"TAP"
"6","(-5575,2875)","0","mstr_standard","I49";
;
HDL_TAP"TRUE"
BODY_TYPE"PLUMBING"
CDS_LIB"mstr_standard";
"B \NAC \NWC"9;
"S \NAC"
BN"27"57;
%"TAP"
"6","(-5575,625)","0","mstr_standard","I5";
;
HDL_TAP"TRUE"
BODY_TYPE"PLUMBING"
CDS_LIB"mstr_standard";
"B \NAC \NWC"10;
"S \NAC"
BN"0"37;
%"TAP"
"6","(-5575,2925)","0","mstr_standard","I50";
;
HDL_TAP"TRUE"
BODY_TYPE"PLUMBING"
CDS_LIB"mstr_standard";
"B \NAC \NWC"9;
"S \NAC"
BN"28"58;
%"TAP"
"6","(-5575,2975)","0","mstr_standard","I51";
;
HDL_TAP"TRUE"
BODY_TYPE"PLUMBING"
CDS_LIB"mstr_standard";
"B \NAC \NWC"9;
"S \NAC"
BN"29"59;
%"TAP"
"6","(-5575,3075)","0","mstr_standard","I52";
;
HDL_TAP"TRUE"
BODY_TYPE"PLUMBING"
CDS_LIB"mstr_standard";
"B \NAC \NWC"9;
"S \NAC"
BN"31"61;
%"TAP"
"6","(-5575,3025)","0","mstr_standard","I53";
;
HDL_TAP"TRUE"
BODY_TYPE"PLUMBING"
CDS_LIB"mstr_standard";
"B \NAC \NWC"9;
"S \NAC"
BN"30"60;
%"TAP"
"6","(-5575,3125)","0","mstr_standard","I54";
;
HDL_TAP"TRUE"
BODY_TYPE"PLUMBING"
CDS_LIB"mstr_standard";
"B \NAC \NWC"9;
"S \NAC"
BN"32"62;
%"TAP"
"6","(-5575,3175)","0","mstr_standard","I55";
;
HDL_TAP"TRUE"
BODY_TYPE"PLUMBING"
CDS_LIB"mstr_standard";
"B \NAC \NWC"9;
"S \NAC"
BN"33"63;
%"TAP"
"6","(-5575,3225)","0","mstr_standard","I56";
;
HDL_TAP"TRUE"
BODY_TYPE"PLUMBING"
CDS_LIB"mstr_standard";
"B \NAC \NWC"9;
"S \NAC"
BN"34"64;
%"TAP"
"6","(-5575,3325)","0","mstr_standard","I57";
;
HDL_TAP"TRUE"
BODY_TYPE"PLUMBING"
CDS_LIB"mstr_standard";
"B \NAC \NWC"9;
"S \NAC"
BN"36"66;
%"TAP"
"6","(-5575,3275)","0","mstr_standard","I58";
;
HDL_TAP"TRUE"
BODY_TYPE"PLUMBING"
CDS_LIB"mstr_standard";
"B \NAC \NWC"9;
"S \NAC"
BN"35"65;
%"TAP"
"6","(-5575,3375)","0","mstr_standard","I59";
;
HDL_TAP"TRUE"
BODY_TYPE"PLUMBING"
CDS_LIB"mstr_standard";
"B \NAC \NWC"9;
"S \NAC"
BN"37"67;
%"TAP"
"6","(-5575,675)","0","mstr_standard","I6";
;
HDL_TAP"TRUE"
BODY_TYPE"PLUMBING"
CDS_LIB"mstr_standard";
"B \NAC \NWC"10;
"S \NAC"
BN"1"38;
%"TAP"
"6","(-5575,3425)","0","mstr_standard","I60";
;
HDL_TAP"TRUE"
BODY_TYPE"PLUMBING"
CDS_LIB"mstr_standard";
"B \NAC \NWC"9;
"S \NAC"
BN"38"68;
%"TAP"
"6","(-5575,3475)","0","mstr_standard","I61";
;
HDL_TAP"TRUE"
BODY_TYPE"PLUMBING"
CDS_LIB"mstr_standard";
"B \NAC \NWC"9;
"S \NAC"
BN"39"69;
%"TAP"
"6","(-5575,3525)","0","mstr_standard","I62";
;
HDL_TAP"TRUE"
BODY_TYPE"PLUMBING"
CDS_LIB"mstr_standard";
"B \NAC \NWC"9;
"S \NAC"
BN"40"70;
%"TAP"
"6","(-5575,3575)","0","mstr_standard","I63";
;
HDL_TAP"TRUE"
BODY_TYPE"PLUMBING"
CDS_LIB"mstr_standard";
"B \NAC \NWC"9;
"S \NAC"
BN"41"71;
%"TAP"
"6","(-5575,3625)","0","mstr_standard","I64";
;
HDL_TAP"TRUE"
BODY_TYPE"PLUMBING"
CDS_LIB"mstr_standard";
"B \NAC \NWC"9;
"S \NAC"
BN"42"72;
%"TAP"
"6","(-5575,3675)","0","mstr_standard","I65";
;
HDL_TAP"TRUE"
BODY_TYPE"PLUMBING"
CDS_LIB"mstr_standard";
"B \NAC \NWC"9;
"S \NAC"
BN"43"73;
%"TAP"
"6","(-5575,3725)","0","mstr_standard","I66";
;
HDL_TAP"TRUE"
BODY_TYPE"PLUMBING"
CDS_LIB"mstr_standard";
"B \NAC \NWC"9;
"S \NAC"
BN"44"74;
%"TAP"
"6","(-5575,3775)","0","mstr_standard","I67";
;
HDL_TAP"TRUE"
BODY_TYPE"PLUMBING"
CDS_LIB"mstr_standard";
"B \NAC \NWC"9;
"S \NAC"
BN"45"75;
%"TAP"
"6","(-5575,3825)","0","mstr_standard","I68";
;
HDL_TAP"TRUE"
BODY_TYPE"PLUMBING"
CDS_LIB"mstr_standard";
"B \NAC \NWC"9;
"S \NAC"
BN"46"76;
%"TAP"
"6","(-5575,3875)","0","mstr_standard","I69";
;
HDL_TAP"TRUE"
BODY_TYPE"PLUMBING"
CDS_LIB"mstr_standard";
"B \NAC \NWC"9;
"S \NAC"
BN"47"77;
%"TAP"
"6","(-5575,775)","0","mstr_standard","I7";
;
HDL_TAP"TRUE"
BODY_TYPE"PLUMBING"
CDS_LIB"mstr_standard";
"B \NAC \NWC"10;
"S \NAC"
BN"3"40;
%"TAP"
"6","(-5575,3925)","0","mstr_standard","I70";
;
HDL_TAP"TRUE"
BODY_TYPE"PLUMBING"
CDS_LIB"mstr_standard";
"B \NAC \NWC"9;
"S \NAC"
BN"48"78;
%"TAP"
"6","(-5575,3975)","0","mstr_standard","I71";
;
HDL_TAP"TRUE"
BODY_TYPE"PLUMBING"
CDS_LIB"mstr_standard";
"B \NAC \NWC"9;
"S \NAC"
BN"49"79;
%"TAP"
"6","(-5575,4025)","0","mstr_standard","I73";
;
HDL_TAP"TRUE"
BODY_TYPE"PLUMBING"
CDS_LIB"mstr_standard";
"B \NAC \NWC"9;
"S \NAC"
BN"50"80;
%"TAP"
"6","(-5575,4075)","0","mstr_standard","I74";
;
HDL_TAP"TRUE"
BODY_TYPE"PLUMBING"
CDS_LIB"mstr_standard";
"B \NAC \NWC"9;
"S \NAC"
BN"51"81;
%"TAP"
"6","(-5575,4125)","0","mstr_standard","I75";
;
HDL_TAP"TRUE"
BODY_TYPE"PLUMBING"
CDS_LIB"mstr_standard";
"B \NAC \NWC"9;
"S \NAC"
BN"52"82;
%"TAP"
"6","(-5575,4175)","0","mstr_standard","I76";
;
HDL_TAP"TRUE"
BODY_TYPE"PLUMBING"
CDS_LIB"mstr_standard";
"B \NAC \NWC"9;
"S \NAC"
BN"53"83;
%"TAP"
"6","(-5575,4225)","0","mstr_standard","I77";
;
HDL_TAP"TRUE"
BODY_TYPE"PLUMBING"
CDS_LIB"mstr_standard";
"B \NAC \NWC"9;
"S \NAC"
BN"54"84;
%"TAP"
"6","(-5575,4275)","0","mstr_standard","I78";
;
HDL_TAP"TRUE"
BODY_TYPE"PLUMBING"
CDS_LIB"mstr_standard";
"B \NAC \NWC"9;
"S \NAC"
BN"55"85;
%"TAP"
"6","(-5575,4325)","0","mstr_standard","I79";
;
HDL_TAP"TRUE"
BODY_TYPE"PLUMBING"
CDS_LIB"mstr_standard";
"B \NAC \NWC"9;
"S \NAC"
BN"56"86;
%"TAP"
"6","(-5575,725)","0","mstr_standard","I8";
;
HDL_TAP"TRUE"
BODY_TYPE"PLUMBING"
CDS_LIB"mstr_standard";
"B \NAC \NWC"10;
"S \NAC"
BN"2"39;
%"TAP"
"6","(-5575,4375)","0","mstr_standard","I80";
;
HDL_TAP"TRUE"
BODY_TYPE"PLUMBING"
CDS_LIB"mstr_standard";
"B \NAC \NWC"9;
"S \NAC"
BN"57"87;
%"TAP"
"6","(-5575,4425)","0","mstr_standard","I81";
;
HDL_TAP"TRUE"
BODY_TYPE"PLUMBING"
CDS_LIB"mstr_standard";
"B \NAC \NWC"9;
"S \NAC"
BN"58"88;
%"TAP"
"6","(-5575,4475)","0","mstr_standard","I82";
;
HDL_TAP"TRUE"
BODY_TYPE"PLUMBING"
CDS_LIB"mstr_standard";
"B \NAC \NWC"9;
"S \NAC"
BN"59"89;
%"TAP"
"6","(-5575,4525)","0","mstr_standard","I83";
;
HDL_TAP"TRUE"
BODY_TYPE"PLUMBING"
CDS_LIB"mstr_standard";
"B \NAC \NWC"9;
"S \NAC"
BN"60"90;
%"TAP"
"6","(-5575,4575)","0","mstr_standard","I84";
;
HDL_TAP"TRUE"
BODY_TYPE"PLUMBING"
CDS_LIB"mstr_standard";
"B \NAC \NWC"9;
"S \NAC"
BN"61"91;
%"TAP"
"6","(-5575,4625)","0","mstr_standard","I85";
;
HDL_TAP"TRUE"
BODY_TYPE"PLUMBING"
CDS_LIB"mstr_standard";
"B \NAC \NWC"9;
"S \NAC"
BN"62"92;
%"TAP"
"6","(-5575,4675)","0","mstr_standard","I86";
;
HDL_TAP"TRUE"
BODY_TYPE"PLUMBING"
CDS_LIB"mstr_standard";
"B \NAC \NWC"9;
"S \NAC"
BN"63"93;
%"TAP"
"6","(-2850,775)","2","mstr_standard","I87";
;
HDL_TAP"TRUE"
BODY_TYPE"PLUMBING"
CDS_LIB"mstr_standard";
"B \NAC \NWC"4;
"S \NAC"
BN"1"116;
%"TAP"
"6","(-2850,725)","2","mstr_standard","I88";
;
HDL_TAP"TRUE"
BODY_TYPE"PLUMBING"
CDS_LIB"mstr_standard";
"B \NAC \NWC"4;
"S \NAC"
BN"0"115;
%"TAP"
"6","(-2850,825)","2","mstr_standard","I89";
;
HDL_TAP"TRUE"
BODY_TYPE"PLUMBING"
CDS_LIB"mstr_standard";
"B \NAC \NWC"5;
"S \NAC"
BN"0"113;
%"TAP"
"6","(-5575,875)","0","mstr_standard","I9";
;
HDL_TAP"TRUE"
BODY_TYPE"PLUMBING"
CDS_LIB"mstr_standard";
"B \NAC \NWC"11;
"S \NAC"
BN"1"34;
%"TAP"
"6","(-2850,875)","2","mstr_standard","I90";
;
HDL_TAP"TRUE"
BODY_TYPE"PLUMBING"
CDS_LIB"mstr_standard";
"B \NAC \NWC"5;
"S \NAC"
BN"1"114;
%"TAP"
"6","(-2850,1075)","2","mstr_standard","I91";
;
HDL_TAP"TRUE"
BODY_TYPE"PLUMBING"
CDS_LIB"mstr_standard";
"B \NAC \NWC"7;
"S \NAC"
BN"2"103;
%"TAP"
"6","(-2850,1025)","2","mstr_standard","I92";
;
HDL_TAP"TRUE"
BODY_TYPE"PLUMBING"
CDS_LIB"mstr_standard";
"B \NAC \NWC"7;
"S \NAC"
BN"1"102;
%"TAP"
"6","(-2850,975)","2","mstr_standard","I93";
;
HDL_TAP"TRUE"
BODY_TYPE"PLUMBING"
CDS_LIB"mstr_standard";
"B \NAC \NWC"7;
"S \NAC"
BN"0"101;
%"TAP"
"6","(-2850,1175)","2","mstr_standard","I94";
;
HDL_TAP"TRUE"
BODY_TYPE"PLUMBING"
CDS_LIB"mstr_standard";
"B \NAC \NWC"7;
"S \NAC"
BN"4"105;
%"TAP"
"6","(-2850,1125)","2","mstr_standard","I95";
;
HDL_TAP"TRUE"
BODY_TYPE"PLUMBING"
CDS_LIB"mstr_standard";
"B \NAC \NWC"7;
"S \NAC"
BN"3"104;
%"TAP"
"6","(-2850,1225)","2","mstr_standard","I96";
;
HDL_TAP"TRUE"
BODY_TYPE"PLUMBING"
CDS_LIB"mstr_standard";
"B \NAC \NWC"7;
"S \NAC"
BN"5"106;
%"TAP"
"6","(-2850,1275)","2","mstr_standard","I97";
;
HDL_TAP"TRUE"
BODY_TYPE"PLUMBING"
CDS_LIB"mstr_standard";
"B \NAC \NWC"7;
"S \NAC"
BN"6"107;
%"TAP"
"6","(-2850,1325)","2","mstr_standard","I98";
;
HDL_TAP"TRUE"
BODY_TYPE"PLUMBING"
CDS_LIB"mstr_standard";
"B \NAC \NWC"7;
"S \NAC"
BN"7"108;
%"TAP"
"6","(-2850,1425)","2","mstr_standard","I99";
;
HDL_TAP"TRUE"
BODY_TYPE"PLUMBING"
CDS_LIB"mstr_standard";
"B \NAC \NWC"8;
"S \NAC"
BN"0"94;
END.
